# T6G (Grand Teton) — schematic netlist excerpt (pin names and nets, part order shuffled) for the footprints in the layout excerpt that follows; sources: Cadence DE-HDL packaged netlist, KiCad conversion of 04192023_DAF0TMB3IC0_F0TG_MB_C_brd_V02_OCP.brd

C2190  Q_CAP  22UF 4V 20% X6S  pkg C0402  page 69 : A = PVDDCR_CPU0_P0 ; B = GND
R6232  Q_RES  160K 1% EMPTY  pkg 0402LF  page 267 : A = HSC_CSOUT ; B = A_HSC_LOW
PC554_3  Q_CAP  22UF 16V 20% X6S  pkg C0805  page 195 : A = SW_P12V_AUX_PVDDCR_CPU0_P0_FLT ; B = GND

(kicad_pcb
	(version 20260206)
	(generator "pcbnew")
	(generator_version "10.0")
	(general
		(thickness 1.6)
		(legacy_teardrops no)
	)
	(paper "A4")
	(title_block
		(title "04192023_DAF0TMB3IC0_F0TG_MB_C_brd_V02_OCP.brd")
		(comment 1 "Grand Teton / footprints 6233-6235 of 8354")
	)
	(layers
		(0 "F.Cu" signal "TOP")
		(4 "In1.Cu" signal "GND")
		(6 "In2.Cu" signal "IN1")
		(8 "In3.Cu" signal "GND1")
		(10 "In4.Cu" signal "IN2")
		(12 "In5.Cu" signal "GND2")
		(14 "In6.Cu" signal "IN3")
		(16 "In7.Cu" signal "GND3")
		(18 "In8.Cu" signal "VCC")
		(20 "In9.Cu" signal "VCC1")
		(22 "In10.Cu" signal "GND4")
		(24 "In11.Cu" signal "IN4")
		(26 "In12.Cu" signal "GND5")
		(28 "In13.Cu" signal "IN5")
		(30 "In14.Cu" signal "GND6")
		(32 "In15.Cu" signal "IN6")
		(34 "In16.Cu" signal "GND7")
		(2 "B.Cu" signal "BOTTOM")
		(9 "F.Adhes" user "F.Adhesive")
		(11 "B.Adhes" user "B.Adhesive")
		(13 "F.Paste" user "Package Geometry/Pastemask Top")
		(15 "B.Paste" user "Package Geometry/Pastemask Bottom")
		(5 "F.SilkS" user "Ref Des/Silkscreen Top")
		(7 "B.SilkS" user "Ref Des/Silkscreen Bottom")
		(1 "F.Mask" user "Board Geometry/Soldermask Top")
		(3 "B.Mask" user "Board Geometry/Soldermask Bottom")
		(17 "Dwgs.User" user "User.Drawings")
		(19 "Cmts.User" user "User.Comments")
		(21 "Eco1.User" user "User.Eco1")
		(23 "Eco2.User" user "User.Eco2")
		(25 "Edge.Cuts" user "Board Geometry/Outline")
		(27 "Margin" user)
		(31 "F.CrtYd" user "Package Geometry/Place Bound Top")
		(29 "B.CrtYd" user "Package Geometry/Place Bound Bottom")
		(35 "F.Fab" user "Ref Des/Assembly Top")
		(33 "B.Fab" user "Ref Des/Assembly Bottom")
	)
	(footprint ""
		(layer "B.Cu")
		(at 358.089454 -246.44731 -120)
		(property "Reference" "C2190"
			(at 0 0 60)
			(layer "B.SilkS")
			(hide yes)
			(effects
				(font
					(size 1.27 1.27)
				)
				(justify mirror)
			)
		)
		(property "Value" ""
			(at 0 0 60)
			(layer "B.Fab")
			(effects
				(font
					(size 1.27 1.27)
				)
				(justify mirror)
			)
		)
		(duplicate_pad_numbers_are_jumpers no)
		(fp_line
			(start 0.787516 0.406438)
			(end 0.787425 -0.40652)
			(stroke
				(width 0.1524)
				(type default)
			)
			(layer "B.SilkS")
		)
		(fp_line
			(start 0.787425 -0.40652)
			(end -0.787516 -0.406438)
			(stroke
				(width 0.1524)
				(type default)
			)
			(layer "B.SilkS")
		)
		(fp_line
			(start -0.787425 0.40652)
			(end 0.787516 0.406438)
			(stroke
				(width 0.1524)
				(type default)
			)
			(layer "B.SilkS")
		)
		(fp_line
			(start -0.787516 -0.406438)
			(end -0.787425 0.40652)
			(stroke
				(width 0.1524)
				(type default)
			)
			(layer "B.SilkS")
		)
		(fp_line
			(start 0.679568 0.304811)
			(end 0.679373 -0.305128)
			(stroke
				(width 0.1)
				(type default)
			)
			(layer "B.Fab")
		)
		(fp_line
			(start 0.120605 0.304905)
			(end 0.679568 0.304811)
			(stroke
				(width 0.1)
				(type default)
			)
			(layer "B.Fab")
		)
		(fp_line
			(start 0.120554 0.279418)
			(end 0.120605 0.304905)
			(stroke
				(width 0.1)
				(type default)
			)
			(layer "B.Fab")
		)
		(fp_line
			(start -0.120316 0.304686)
			(end -0.12024 0.279419)
			(stroke
				(width 0.1)
				(type default)
			)
			(layer "B.Fab")
		)
		(fp_line
			(start -0.12024 0.279419)
			(end 0.120554 0.279418)
			(stroke
				(width 0.1)
				(type default)
			)
			(layer "B.Fab")
		)
		(fp_line
			(start 0.679373 -0.305128)
			(end 0.120629 -0.30516)
			(stroke
				(width 0.1)
				(type default)
			)
			(layer "B.Fab")
		)
		(fp_line
			(start -0.6795 0.304908)
			(end -0.120316 0.304686)
			(stroke
				(width 0.1)
				(type default)
			)
			(layer "B.Fab")
		)
		(fp_line
			(start 0.120587 -0.279326)
			(end -0.120554 -0.279418)
			(stroke
				(width 0.1)
				(type default)
			)
			(layer "B.Fab")
		)
		(fp_line
			(start 0.120629 -0.30516)
			(end 0.120587 -0.279326)
			(stroke
				(width 0.1)
				(type default)
			)
			(layer "B.Fab")
		)
		(fp_line
			(start -0.120554 -0.279418)
			(end -0.120605 -0.304905)
			(stroke
				(width 0.1)
				(type default)
			)
			(layer "B.Fab")
		)
		(fp_line
			(start -0.120605 -0.304905)
			(end -0.679568 -0.304811)
			(stroke
				(width 0.1)
				(type default)
			)
			(layer "B.Fab")
		)
		(fp_line
			(start -0.679568 -0.304811)
			(end -0.6795 0.304908)
			(stroke
				(width 0.1)
				(type default)
			)
			(layer "B.Fab")
		)
		(pad "1" smd circle
			(at 0.40005 0 60)
			(size 0 0)
			(layers "B.Cu" "B.Mask" "B.Paste")
			(net "PVDDCR_CPU0_P0")
		)
		(pad "2" smd circle
			(at -0.40005 0 60)
			(size 0 0)
			(layers "B.Cu" "B.Mask" "B.Paste")
			(net "GND")
		)
	)
	(footprint ""
		(layer "B.Cu")
		(at 183.294528 -425.674282 -90)
		(property "Reference" "R6232"
			(at 0 0 90)
			(layer "B.SilkS")
			(hide yes)
			(effects
				(font
					(size 1.27 1.27)
				)
				(justify mirror)
			)
		)
		(property "Value" ""
			(at 0 0 90)
			(layer "B.Fab")
			(effects
				(font
					(size 1.27 1.27)
				)
				(justify mirror)
			)
		)
		(duplicate_pad_numbers_are_jumpers no)
		(fp_line
			(start -0.7874 0.4064)
			(end 0.7874 0.4064)
			(stroke
				(width 0.1524)
				(type default)
			)
			(layer "B.SilkS")
		)
		(fp_line
			(start 0.7874 0.4064)
			(end 0.7874 -0.4064)
			(stroke
				(width 0.1524)
				(type default)
			)
			(layer "B.SilkS")
		)
		(fp_line
			(start -0.7874 -0.4064)
			(end -0.7874 0.4064)
			(stroke
				(width 0.1524)
				(type default)
			)
			(layer "B.SilkS")
		)
		(fp_line
			(start 0.7874 -0.4064)
			(end -0.7874 -0.4064)
			(stroke
				(width 0.1524)
				(type default)
			)
			(layer "B.SilkS")
		)
		(fp_line
			(start -0.67945 0.3048)
			(end -0.120396 0.3048)
			(stroke
				(width 0.1)
				(type default)
			)
			(layer "B.Fab")
		)
		(fp_line
			(start -0.120396 0.3048)
			(end -0.120396 0.2794)
			(stroke
				(width 0.1)
				(type default)
			)
			(layer "B.Fab")
		)
		(fp_line
			(start 0.12065 0.3048)
			(end 0.67945 0.3048)
			(stroke
				(width 0.1)
				(type default)
			)
			(layer "B.Fab")
		)
		(fp_line
			(start 0.67945 0.3048)
			(end 0.67945 -0.305054)
			(stroke
				(width 0.1)
				(type default)
			)
			(layer "B.Fab")
		)
		(fp_line
			(start -0.120396 0.2794)
			(end 0.12065 0.2794)
			(stroke
				(width 0.1)
				(type default)
			)
			(layer "B.Fab")
		)
		(fp_line
			(start 0.12065 0.2794)
			(end 0.12065 0.3048)
			(stroke
				(width 0.1)
				(type default)
			)
			(layer "B.Fab")
		)
		(fp_line
			(start -0.12065 -0.2794)
			(end -0.12065 -0.3048)
			(stroke
				(width 0.1)
				(type default)
			)
			(layer "B.Fab")
		)
		(fp_line
			(start 0.12065 -0.2794)
			(end -0.12065 -0.2794)
			(stroke
				(width 0.1)
				(type default)
			)
			(layer "B.Fab")
		)
		(fp_line
			(start -0.67945 -0.3048)
			(end -0.67945 0.3048)
			(stroke
				(width 0.1)
				(type default)
			)
			(layer "B.Fab")
		)
		(fp_line
			(start -0.12065 -0.3048)
			(end -0.67945 -0.3048)
			(stroke
				(width 0.1)
				(type default)
			)
			(layer "B.Fab")
		)
		(fp_line
			(start 0.12065 -0.305054)
			(end 0.12065 -0.2794)
			(stroke
				(width 0.1)
				(type default)
			)
			(layer "B.Fab")
		)
		(fp_line
			(start 0.67945 -0.305054)
			(end 0.12065 -0.305054)
			(stroke
				(width 0.1)
				(type default)
			)
			(layer "B.Fab")
		)
		(pad "1" smd circle
			(at 0.40005 0 90)
			(size 0 0)
			(layers "B.Cu" "B.Mask" "B.Paste")
			(net "HSC_CSOUT")
		)
		(pad "2" smd circle
			(at -0.40005 0 90)
			(size 0 0)
			(layers "B.Cu" "B.Mask" "B.Paste")
			(net "A_HSC_LOW")
		)
	)
	(footprint ""
		(layer "B.Cu")
		(at 379.888496 -178.977798 90)
		(property "Reference" "PC554_3"
			(at 0 0 90)
			(layer "B.SilkS")
			(hide yes)
			(effects
				(font
					(size 1.27 1.27)
				)
				(justify mirror)
			)
		)
		(property "Value" ""
			(at 0 0 90)
			(layer "B.Fab")
			(effects
				(font
					(size 1.27 1.27)
				)
				(justify mirror)
			)
		)
		(duplicate_pad_numbers_are_jumpers no)
		(fp_line
			(start 1.524 -0.762)
			(end -1.524 -0.762)
			(stroke
				(width 0.1524)
				(type default)
			)
			(layer "B.SilkS")
		)
		(fp_line
			(start -1.524 -0.762)
			(end -1.524 0.762)
			(stroke
				(width 0.1524)
				(type default)
			)
			(layer "B.SilkS")
		)
		(fp_line
			(start 1.524 0.762)
			(end 1.524 -0.762)
			(stroke
				(width 0.1524)
				(type default)
			)
			(layer "B.SilkS")
		)
		(fp_line
			(start -1.524 0.762)
			(end 1.524 0.762)
			(stroke
				(width 0.1524)
				(type default)
			)
			(layer "B.SilkS")
		)
		(fp_line
			(start 1.1049 -0.724916)
			(end 1.1049 0.724916)
			(stroke
				(width 0.1)
				(type default)
			)
			(layer "B.Fab")
		)
		(fp_line
			(start -1.1049 -0.724916)
			(end 1.1049 -0.724916)
			(stroke
				(width 0.1)
				(type default)
			)
			(layer "B.Fab")
		)
		(fp_line
			(start 1.1049 0.724916)
			(end -1.1049 0.724916)
			(stroke
				(width 0.1)
				(type default)
			)
			(layer "B.Fab")
		)
		(fp_line
			(start -1.1049 0.724916)
			(end -1.1049 -0.724916)
			(stroke
				(width 0.1)
				(type default)
			)
			(layer "B.Fab")
		)
		(pad "1" smd rect
			(at 0.889 0 90)
			(size 1.016 1.27)
			(layers "B.Cu" "B.Mask" "B.Paste")
			(net "SW_P12V_AUX_PVDDCR_CPU0_P0_FLT")
		)
		(pad "2" smd rect
			(at -0.889 0 90)
			(size 1.016 1.27)
			(layers "B.Cu" "B.Mask" "B.Paste")
			(net "GND")
		)
	)
)
